(kicad_pcb
	(version 20260206)
	(generator "pcbnew")
	(generator_version "10.0")
	(general
		(thickness 1.6)
		(legacy_teardrops no)
	)
	(paper "A4")
	(title_block
		(title "03242023_DA0F0TMBIJ0_F0T_Motherboard_J_brd_V01_OCP.brd")
		(comment 1 "Grand Teton / footprints 347-350 of 6105")
	)
	(layers
		(0 "F.Cu" signal "TOP")
		(4 "In1.Cu" signal "GND")
		(6 "In2.Cu" signal "IN1")
		(8 "In3.Cu" signal "GND1")
		(10 "In4.Cu" signal "IN2")
		(12 "In5.Cu" signal "GND2")
		(14 "In6.Cu" signal "IN3")
		(16 "In7.Cu" signal "GND3")
		(18 "In8.Cu" signal "VCC")
		(20 "In9.Cu" signal "VCC1")
		(22 "In10.Cu" signal "GND4")
		(24 "In11.Cu" signal "IN4")
		(26 "In12.Cu" signal "GND5")
		(28 "In13.Cu" signal "IN5")
		(30 "In14.Cu" signal "GND6")
		(32 "In15.Cu" signal "IN6")
		(34 "In16.Cu" signal "GND7")
		(2 "B.Cu" signal "BOTTOM")
		(9 "F.Adhes" user "F.Adhesive")
		(11 "B.Adhes" user "B.Adhesive")
		(13 "F.Paste" user "Package Geometry/Pastemask Top")
		(15 "B.Paste" user "Package Geometry/Pastemask Bottom")
		(5 "F.SilkS" user "Ref Des/Silkscreen Top")
		(7 "B.SilkS" user "Ref Des/Silkscreen Bottom")
		(1 "F.Mask" user "Board Geometry/Soldermask Top")
		(3 "B.Mask" user "Board Geometry/Soldermask Bottom")
		(17 "Dwgs.User" user "User.Drawings")
		(19 "Cmts.User" user "User.Comments")
		(21 "Eco1.User" user "User.Eco1")
		(23 "Eco2.User" user "User.Eco2")
		(25 "Edge.Cuts" user "Board Geometry/Outline")
		(27 "Margin" user)
		(31 "F.CrtYd" user "Package Geometry/Place Bound Top")
		(29 "B.CrtYd" user "Package Geometry/Place Bound Bottom")
		(35 "F.Fab" user "Ref Des/Assembly Top")
		(33 "B.Fab" user "Ref Des/Assembly Bottom")
	)
	(footprint ""
		(layer "F.Cu")
		(at 122.555 -55.971948)
		(property "Reference" "U327"
			(at 1.27 -3.52933 0)
			(unlocked yes)
			(layer "F.SilkS")
			(effects
				(font
					(size 0.7874 0.5842)
					(thickness 0.1524)
				)
				(justify left)
			)
		)
		(property "Value" ""
			(at 0 0 0)
			(layer "F.Fab")
			(effects
				(font
					(size 1.27 1.27)
				)
			)
		)
		(duplicate_pad_numbers_are_jumpers no)
		(fp_line
			(start -2.0066 -2.5527)
			(end -0.5715 -2.5527)
			(stroke
				(width 0.1524)
				(type default)
			)
			(layer "F.SilkS")
		)
		(fp_line
			(start -2.0066 2.5527)
			(end -2.0066 -2.5527)
			(stroke
				(width 0.1524)
				(type default)
			)
			(layer "F.SilkS")
		)
		(fp_line
			(start -0.5715 -2.5527)
			(end 0 -1.9812)
			(stroke
				(width 0.1524)
				(type default)
			)
			(layer "F.SilkS")
		)
		(fp_line
			(start 0 -1.9812)
			(end 0.5715 -2.5527)
			(stroke
				(width 0.1524)
				(type default)
			)
			(layer "F.SilkS")
		)
		(fp_line
			(start 0.5715 -2.5527)
			(end 2.0066 -2.5527)
			(stroke
				(width 0.1524)
				(type default)
			)
			(layer "F.SilkS")
		)
		(fp_line
			(start 2.0066 -2.5527)
			(end 2.0066 2.5527)
			(stroke
				(width 0.1524)
				(type default)
			)
			(layer "F.SilkS")
		)
		(fp_line
			(start 2.0066 2.5527)
			(end -2.0066 2.5527)
			(stroke
				(width 0.1524)
				(type default)
			)
			(layer "F.SilkS")
		)
		(fp_poly
			(pts
				(xy -4.36372 -1.608328) (xy -4.36372 -2.233168) (xy -3.81 -1.905)
			)
			(stroke
				(width 0)
				(type default)
			)
			(fill yes)
			(layer "F.SilkS")
		)
		(fp_line
			(start -2.249932 -2.549906)
			(end 2.249932 -2.549906)
			(stroke
				(width 0.1)
				(type default)
			)
			(layer "F.Fab")
		)
		(fp_line
			(start -2.249932 2.549906)
			(end -2.249932 -2.549906)
			(stroke
				(width 0.1)
				(type default)
			)
			(layer "F.Fab")
		)
		(fp_line
			(start 2.249932 -2.549906)
			(end 2.249932 2.549906)
			(stroke
				(width 0.1)
				(type default)
			)
			(layer "F.Fab")
		)
		(fp_line
			(start 2.249932 2.549906)
			(end -2.249932 2.549906)
			(stroke
				(width 0.1)
				(type default)
			)
			(layer "F.Fab")
		)
		(fp_poly
			(pts
				(xy -4.36372 -1.608328) (xy -4.36372 -2.233168) (xy -3.81 -1.905)
			)
			(stroke
				(width 0)
				(type default)
			)
			(fill yes)
			(layer "F.Fab")
		)
		(pad "1" smd rect
			(at -2.921 -1.949958 270)
			(size 0.3556 1.4986)
			(layers "F.Cu" "F.Mask" "F.Paste")
			(net "JTAG_BMC_SW_R_OE")
		)
		(pad "2" smd rect
			(at -2.921 -1.299972 270)
			(size 0.3556 1.4986)
			(layers "F.Cu" "F.Mask" "F.Paste")
			(net "JTAG_BMC_TCK_R")
		)
		(pad "3" smd rect
			(at -2.921 -0.649986 270)
			(size 0.3556 1.4986)
			(layers "F.Cu" "F.Mask" "F.Paste")
			(net "JTAG_BMC_SW_TCK_R")
		)
		(pad "4" smd rect
			(at -2.921 0 270)
			(size 0.3556 1.4986)
			(layers "F.Cu" "F.Mask" "F.Paste")
			(net "JTAG_BMC_SW_R_OE")
		)
		(pad "5" smd rect
			(at -2.921 0.649986 270)
			(size 0.3556 1.4986)
			(layers "F.Cu" "F.Mask" "F.Paste")
			(net "JTAG_BMC_TMS_R")
		)
		(pad "6" smd rect
			(at -2.921 1.299972 270)
			(size 0.3556 1.4986)
			(layers "F.Cu" "F.Mask" "F.Paste")
			(net "JTAG_BMC_SW_TMS_R")
		)
		(pad "7" smd rect
			(at -2.921 1.949958 270)
			(size 0.3556 1.4986)
			(layers "F.Cu" "F.Mask" "F.Paste")
			(net "GND")
		)
		(pad "8" smd rect
			(at 2.921 1.949958 270)
			(size 0.3556 1.4986)
			(layers "F.Cu" "F.Mask" "F.Paste")
			(net "JTAG_BMC_SW_TDI_R")
		)
		(pad "9" smd rect
			(at 2.921 1.299972 270)
			(size 0.3556 1.4986)
			(layers "F.Cu" "F.Mask" "F.Paste")
			(net "JTAG_BMC_TDI_R")
		)
		(pad "10" smd rect
			(at 2.921 0.649986 270)
			(size 0.3556 1.4986)
			(layers "F.Cu" "F.Mask" "F.Paste")
			(net "JTAG_BMC_SW_R_OE")
		)
		(pad "11" smd rect
			(at 2.921 0 270)
			(size 0.3556 1.4986)
			(layers "F.Cu" "F.Mask" "F.Paste")
			(net "JTAG_BMC_SW_TDO_R")
		)
		(pad "12" smd rect
			(at 2.921 -0.649986 270)
			(size 0.3556 1.4986)
			(layers "F.Cu" "F.Mask" "F.Paste")
			(net "JTAG_BMC_TDO_R")
		)
		(pad "13" smd rect
			(at 2.921 -1.299972 270)
			(size 0.3556 1.4986)
			(layers "F.Cu" "F.Mask" "F.Paste")
			(net "JTAG_BMC_SW_R_OE")
		)
		(pad "14" smd rect
			(at 2.921 -1.949958 270)
			(size 0.3556 1.4986)
			(layers "F.Cu" "F.Mask" "F.Paste")
			(net "P3V3_AUX")
		)
	)
	(footprint ""
		(layer "F.Cu")
		(at 236.649768 -192.499996)
		(property "Reference" "H94"
			(at -4.87172 -5.123688 0)
			(unlocked yes)
			(layer "F.SilkS")
			(effects
				(font
					(size 0.7874 0.5842)
					(thickness 0.1524)
				)
				(justify left)
			)
		)
		(property "Value" ""
			(at 0 0 0)
			(layer "F.Fab")
			(effects
				(font
					(size 1.27 1.27)
				)
			)
		)
		(duplicate_pad_numbers_are_jumpers no)
		(pad "1" thru_hole circle
			(at 0 0)
			(size 10.0076 10.0076)
			(drill 5.6134)
			(layers "*.Cu" "*.Mask")
			(remove_unused_layers no)
			(net "GND")
			(clearance -1.9431)
		)
	)
	(footprint ""
		(layer "F.Cu")
		(at 223.716088 -223.09709 -90)
		(property "Reference" "C568"
			(at 0 0 270)
			(layer "F.SilkS")
			(hide yes)
			(effects
				(font
					(size 1.27 1.27)
				)
			)
		)
		(property "Value" ""
			(at 0 0 270)
			(layer "F.Fab")
			(effects
				(font
					(size 1.27 1.27)
				)
			)
		)
		(duplicate_pad_numbers_are_jumpers no)
		(fp_line
			(start -0.7874 0.4064)
			(end -0.7874 -0.4064)
			(stroke
				(width 0.1524)
				(type default)
			)
			(layer "F.SilkS")
		)
		(fp_line
			(start 0.7874 0.4064)
			(end -0.7874 0.4064)
			(stroke
				(width 0.1524)
				(type default)
			)
			(layer "F.SilkS")
		)
		(fp_line
			(start -0.7874 -0.4064)
			(end 0.7874 -0.4064)
			(stroke
				(width 0.1524)
				(type default)
			)
			(layer "F.SilkS")
		)
		(fp_line
			(start 0.7874 -0.4064)
			(end 0.7874 0.4064)
			(stroke
				(width 0.1524)
				(type default)
			)
			(layer "F.SilkS")
		)
		(fp_line
			(start -0.67945 0.3048)
			(end -0.67945 -0.305054)
			(stroke
				(width 0.1)
				(type default)
			)
			(layer "F.Fab")
		)
		(fp_line
			(start -0.12065 0.3048)
			(end -0.67945 0.3048)
			(stroke
				(width 0.1)
				(type default)
			)
			(layer "F.Fab")
		)
		(fp_line
			(start 0.120396 0.3048)
			(end 0.120396 0.2794)
			(stroke
				(width 0.1)
				(type default)
			)
			(layer "F.Fab")
		)
		(fp_line
			(start 0.67945 0.3048)
			(end 0.120396 0.3048)
			(stroke
				(width 0.1)
				(type default)
			)
			(layer "F.Fab")
		)
		(fp_line
			(start -0.12065 0.2794)
			(end -0.12065 0.3048)
			(stroke
				(width 0.1)
				(type default)
			)
			(layer "F.Fab")
		)
		(fp_line
			(start 0.120396 0.2794)
			(end -0.12065 0.2794)
			(stroke
				(width 0.1)
				(type default)
			)
			(layer "F.Fab")
		)
		(fp_line
			(start -0.12065 -0.2794)
			(end 0.12065 -0.2794)
			(stroke
				(width 0.1)
				(type default)
			)
			(layer "F.Fab")
		)
		(fp_line
			(start 0.12065 -0.2794)
			(end 0.12065 -0.3048)
			(stroke
				(width 0.1)
				(type default)
			)
			(layer "F.Fab")
		)
		(fp_line
			(start 0.12065 -0.3048)
			(end 0.67945 -0.3048)
			(stroke
				(width 0.1)
				(type default)
			)
			(layer "F.Fab")
		)
		(fp_line
			(start 0.67945 -0.3048)
			(end 0.67945 0.3048)
			(stroke
				(width 0.1)
				(type default)
			)
			(layer "F.Fab")
		)
		(fp_line
			(start -0.67945 -0.305054)
			(end -0.12065 -0.305054)
			(stroke
				(width 0.1)
				(type default)
			)
			(layer "F.Fab")
		)
		(fp_line
			(start -0.12065 -0.305054)
			(end -0.12065 -0.2794)
			(stroke
				(width 0.1)
				(type default)
			)
			(layer "F.Fab")
		)
		(pad "1" smd circle
			(at -0.40005 0 270)
			(size 0 0)
			(layers "F.Cu" "F.Mask" "F.Paste")
			(net "PVNN_TERM_CPU1")
		)
		(pad "2" smd circle
			(at 0.40005 0 270)
			(size 0 0)
			(layers "F.Cu" "F.Mask" "F.Paste")
			(net "GND")
		)
	)
	(footprint ""
		(layer "F.Cu")
		(at 366.4458 -15.255748 180)
		(property "Reference" "C2345"
			(at 0 0 180)
			(layer "F.SilkS")
			(hide yes)
			(effects
				(font
					(size 1.27 1.27)
				)
			)
		)
		(property "Value" ""
			(at 0 0 180)
			(layer "F.Fab")
			(effects
				(font
					(size 1.27 1.27)
				)
			)
		)
		(duplicate_pad_numbers_are_jumpers no)
		(fp_line
			(start 0.7874 0.4064)
			(end -0.7874 0.4064)
			(stroke
				(width 0.1524)
				(type default)
			)
			(layer "F.SilkS")
		)
		(fp_line
			(start 0.7874 -0.4064)
			(end 0.7874 0.4064)
			(stroke
				(width 0.1524)
				(type default)
			)
			(layer "F.SilkS")
		)
		(fp_line
			(start -0.7874 0.4064)
			(end -0.7874 -0.4064)
			(stroke
				(width 0.1524)
				(type default)
			)
			(layer "F.SilkS")
		)
		(fp_line
			(start -0.7874 -0.4064)
			(end 0.7874 -0.4064)
			(stroke
				(width 0.1524)
				(type default)
			)
			(layer "F.SilkS")
		)
		(fp_line
			(start 0.67945 0.3048)
			(end 0.120396 0.3048)
			(stroke
				(width 0.1)
				(type default)
			)
			(layer "F.Fab")
		)
		(fp_line
			(start 0.67945 -0.3048)
			(end 0.67945 0.3048)
			(stroke
				(width 0.1)
				(type default)
			)
			(layer "F.Fab")
		)
		(fp_line
			(start 0.12065 -0.2794)
			(end 0.12065 -0.3048)
			(stroke
				(width 0.1)
				(type default)
			)
			(layer "F.Fab")
		)
		(fp_line
			(start 0.12065 -0.3048)
			(end 0.67945 -0.3048)
			(stroke
				(width 0.1)
				(type default)
			)
			(layer "F.Fab")
		)
		(fp_line
			(start 0.120396 0.3048)
			(end 0.120396 0.2794)
			(stroke
				(width 0.1)
				(type default)
			)
			(layer "F.Fab")
		)
		(fp_line
			(start 0.120396 0.2794)
			(end -0.12065 0.2794)
			(stroke
				(width 0.1)
				(type default)
			)
			(layer "F.Fab")
		)
		(fp_line
			(start -0.12065 0.3048)
			(end -0.67945 0.3048)
			(stroke
				(width 0.1)
				(type default)
			)
			(layer "F.Fab")
		)
		(fp_line
			(start -0.12065 0.2794)
			(end -0.12065 0.3048)
			(stroke
				(width 0.1)
				(type default)
			)
			(layer "F.Fab")
		)
		(fp_line
			(start -0.12065 -0.2794)
			(end 0.12065 -0.2794)
			(stroke
				(width 0.1)
				(type default)
			)
			(layer "F.Fab")
		)
		(fp_line
			(start -0.12065 -0.305054)
			(end -0.12065 -0.2794)
			(stroke
				(width 0.1)
				(type default)
			)
			(layer "F.Fab")
		)
		(fp_line
			(start -0.67945 0.3048)
			(end -0.67945 -0.305054)
			(stroke
				(width 0.1)
				(type default)
			)
			(layer "F.Fab")
		)
		(fp_line
			(start -0.67945 -0.305054)
			(end -0.12065 -0.305054)
			(stroke
				(width 0.1)
				(type default)
			)
			(layer "F.Fab")
		)
		(pad "1" smd circle
			(at -0.40005 0 180)
			(size 0 0)
			(layers "F.Cu" "F.Mask" "F.Paste")
			(net "P3V3_AUX")
		)
		(pad "2" smd circle
			(at 0.40005 0 180)
			(size 0 0)
			(layers "F.Cu" "F.Mask" "F.Paste")
			(net "GND")
		)
	)
)
